# T6G (Grand Teton) — schematic netlist excerpt (pin names and nets, part order shuffled) for the footprints in the layout excerpt that follows; sources: Cadence DE-HDL packaged netlist, KiCad conversion of 04192023_DAF0TMB3IC0_F0TG_MB_C_brd_V02_OCP.brd

PR3999  Q_RES  24.3K 1% CHIP  pkg 0402LF  page 152 : A = P12V_SCM_ISET ; B = GND
R1321  Q_RES  33 5% CHIP  pkg 0402LF  page 151 : A = SMB_VR_3V3STBY_SCL ; B = SMB_SCM_2_R1_SCL
R746  Q_RES  20K 1% CHIP  pkg 0201LF  page 331 : A = RT_CPU1_P1_ADDR2 ; B = GND

(kicad_pcb
	(version 20260206)
	(generator "pcbnew")
	(generator_version "10.0")
	(general
		(thickness 1.6)
		(legacy_teardrops no)
	)
	(paper "A4")
	(title_block
		(title "04192023_DAF0TMB3IC0_F0TG_MB_C_brd_V02_OCP.brd")
		(comment 1 "Grand Teton / footprints 2233-2235 of 8354")
	)
	(layers
		(0 "F.Cu" signal "TOP")
		(4 "In1.Cu" signal "GND")
		(6 "In2.Cu" signal "IN1")
		(8 "In3.Cu" signal "GND1")
		(10 "In4.Cu" signal "IN2")
		(12 "In5.Cu" signal "GND2")
		(14 "In6.Cu" signal "IN3")
		(16 "In7.Cu" signal "GND3")
		(18 "In8.Cu" signal "VCC")
		(20 "In9.Cu" signal "VCC1")
		(22 "In10.Cu" signal "GND4")
		(24 "In11.Cu" signal "IN4")
		(26 "In12.Cu" signal "GND5")
		(28 "In13.Cu" signal "IN5")
		(30 "In14.Cu" signal "GND6")
		(32 "In15.Cu" signal "IN6")
		(34 "In16.Cu" signal "GND7")
		(2 "B.Cu" signal "BOTTOM")
		(9 "F.Adhes" user "F.Adhesive")
		(11 "B.Adhes" user "B.Adhesive")
		(13 "F.Paste" user "Package Geometry/Pastemask Top")
		(15 "B.Paste" user "Package Geometry/Pastemask Bottom")
		(5 "F.SilkS" user "Ref Des/Silkscreen Top")
		(7 "B.SilkS" user "Ref Des/Silkscreen Bottom")
		(1 "F.Mask" user "Board Geometry/Soldermask Top")
		(3 "B.Mask" user "Board Geometry/Soldermask Bottom")
		(17 "Dwgs.User" user "User.Drawings")
		(19 "Cmts.User" user "User.Comments")
		(21 "Eco1.User" user "User.Eco1")
		(23 "Eco2.User" user "User.Eco2")
		(25 "Edge.Cuts" user "Board Geometry/Outline")
		(27 "Margin" user)
		(31 "F.CrtYd" user "Package Geometry/Place Bound Top")
		(29 "B.CrtYd" user "Package Geometry/Place Bound Bottom")
		(35 "F.Fab" user "Ref Des/Assembly Top")
		(33 "B.Fab" user "Ref Des/Assembly Bottom")
	)
	(footprint ""
		(layer "F.Cu")
		(at 178.044602 -32.950912 90)
		(property "Reference" "PR3999"
			(at 0 0 90)
			(layer "F.SilkS")
			(hide yes)
			(effects
				(font
					(size 1.27 1.27)
				)
			)
		)
		(property "Value" ""
			(at 0 0 90)
			(layer "F.Fab")
			(effects
				(font
					(size 1.27 1.27)
				)
			)
		)
		(duplicate_pad_numbers_are_jumpers no)
		(fp_line
			(start 0.7874 -0.4064)
			(end 0.7874 0.4064)
			(stroke
				(width 0.1524)
				(type default)
			)
			(layer "F.SilkS")
		)
		(fp_line
			(start -0.7874 -0.4064)
			(end 0.7874 -0.4064)
			(stroke
				(width 0.1524)
				(type default)
			)
			(layer "F.SilkS")
		)
		(fp_line
			(start 0.7874 0.4064)
			(end -0.7874 0.4064)
			(stroke
				(width 0.1524)
				(type default)
			)
			(layer "F.SilkS")
		)
		(fp_line
			(start -0.7874 0.4064)
			(end -0.7874 -0.4064)
			(stroke
				(width 0.1524)
				(type default)
			)
			(layer "F.SilkS")
		)
		(fp_line
			(start -0.12065 -0.305054)
			(end -0.12065 -0.2794)
			(stroke
				(width 0.1)
				(type default)
			)
			(layer "F.Fab")
		)
		(fp_line
			(start -0.67945 -0.305054)
			(end -0.12065 -0.305054)
			(stroke
				(width 0.1)
				(type default)
			)
			(layer "F.Fab")
		)
		(fp_line
			(start 0.67945 -0.3048)
			(end 0.67945 0.3048)
			(stroke
				(width 0.1)
				(type default)
			)
			(layer "F.Fab")
		)
		(fp_line
			(start 0.12065 -0.3048)
			(end 0.67945 -0.3048)
			(stroke
				(width 0.1)
				(type default)
			)
			(layer "F.Fab")
		)
		(fp_line
			(start 0.12065 -0.2794)
			(end 0.12065 -0.3048)
			(stroke
				(width 0.1)
				(type default)
			)
			(layer "F.Fab")
		)
		(fp_line
			(start -0.12065 -0.2794)
			(end 0.12065 -0.2794)
			(stroke
				(width 0.1)
				(type default)
			)
			(layer "F.Fab")
		)
		(fp_line
			(start 0.120396 0.2794)
			(end -0.12065 0.2794)
			(stroke
				(width 0.1)
				(type default)
			)
			(layer "F.Fab")
		)
		(fp_line
			(start -0.12065 0.2794)
			(end -0.12065 0.3048)
			(stroke
				(width 0.1)
				(type default)
			)
			(layer "F.Fab")
		)
		(fp_line
			(start 0.67945 0.3048)
			(end 0.120396 0.3048)
			(stroke
				(width 0.1)
				(type default)
			)
			(layer "F.Fab")
		)
		(fp_line
			(start 0.120396 0.3048)
			(end 0.120396 0.2794)
			(stroke
				(width 0.1)
				(type default)
			)
			(layer "F.Fab")
		)
		(fp_line
			(start -0.12065 0.3048)
			(end -0.67945 0.3048)
			(stroke
				(width 0.1)
				(type default)
			)
			(layer "F.Fab")
		)
		(fp_line
			(start -0.67945 0.3048)
			(end -0.67945 -0.305054)
			(stroke
				(width 0.1)
				(type default)
			)
			(layer "F.Fab")
		)
		(pad "1" smd circle
			(at -0.40005 0 90)
			(size 0 0)
			(layers "F.Cu" "F.Mask" "F.Paste")
			(net "P12V_SCM_ISET")
		)
		(pad "2" smd circle
			(at 0.40005 0 90)
			(size 0 0)
			(layers "F.Cu" "F.Mask" "F.Paste")
			(net "GND")
		)
	)
	(footprint ""
		(layer "F.Cu")
		(at 22.479 -366.903)
		(property "Reference" "R1321"
			(at 0 0 0)
			(layer "F.SilkS")
			(hide yes)
			(effects
				(font
					(size 1.27 1.27)
				)
			)
		)
		(property "Value" ""
			(at 0 0 0)
			(layer "F.Fab")
			(effects
				(font
					(size 1.27 1.27)
				)
			)
		)
		(duplicate_pad_numbers_are_jumpers no)
		(fp_line
			(start -0.7874 -0.4064)
			(end 0.7874 -0.4064)
			(stroke
				(width 0.1524)
				(type default)
			)
			(layer "F.SilkS")
		)
		(fp_line
			(start -0.7874 0.4064)
			(end -0.7874 -0.4064)
			(stroke
				(width 0.1524)
				(type default)
			)
			(layer "F.SilkS")
		)
		(fp_line
			(start 0.7874 -0.4064)
			(end 0.7874 0.4064)
			(stroke
				(width 0.1524)
				(type default)
			)
			(layer "F.SilkS")
		)
		(fp_line
			(start 0.7874 0.4064)
			(end -0.7874 0.4064)
			(stroke
				(width 0.1524)
				(type default)
			)
			(layer "F.SilkS")
		)
		(fp_line
			(start -0.67945 -0.305054)
			(end -0.12065 -0.305054)
			(stroke
				(width 0.1)
				(type default)
			)
			(layer "F.Fab")
		)
		(fp_line
			(start -0.67945 0.3048)
			(end -0.67945 -0.305054)
			(stroke
				(width 0.1)
				(type default)
			)
			(layer "F.Fab")
		)
		(fp_line
			(start -0.12065 -0.305054)
			(end -0.12065 -0.2794)
			(stroke
				(width 0.1)
				(type default)
			)
			(layer "F.Fab")
		)
		(fp_line
			(start -0.12065 -0.2794)
			(end 0.12065 -0.2794)
			(stroke
				(width 0.1)
				(type default)
			)
			(layer "F.Fab")
		)
		(fp_line
			(start -0.12065 0.2794)
			(end -0.12065 0.3048)
			(stroke
				(width 0.1)
				(type default)
			)
			(layer "F.Fab")
		)
		(fp_line
			(start -0.12065 0.3048)
			(end -0.67945 0.3048)
			(stroke
				(width 0.1)
				(type default)
			)
			(layer "F.Fab")
		)
		(fp_line
			(start 0.120396 0.2794)
			(end -0.12065 0.2794)
			(stroke
				(width 0.1)
				(type default)
			)
			(layer "F.Fab")
		)
		(fp_line
			(start 0.120396 0.3048)
			(end 0.120396 0.2794)
			(stroke
				(width 0.1)
				(type default)
			)
			(layer "F.Fab")
		)
		(fp_line
			(start 0.12065 -0.3048)
			(end 0.67945 -0.3048)
			(stroke
				(width 0.1)
				(type default)
			)
			(layer "F.Fab")
		)
		(fp_line
			(start 0.12065 -0.2794)
			(end 0.12065 -0.3048)
			(stroke
				(width 0.1)
				(type default)
			)
			(layer "F.Fab")
		)
		(fp_line
			(start 0.67945 -0.3048)
			(end 0.67945 0.3048)
			(stroke
				(width 0.1)
				(type default)
			)
			(layer "F.Fab")
		)
		(fp_line
			(start 0.67945 0.3048)
			(end 0.120396 0.3048)
			(stroke
				(width 0.1)
				(type default)
			)
			(layer "F.Fab")
		)
		(pad "1" smd circle
			(at -0.40005 0)
			(size 0 0)
			(layers "F.Cu" "F.Mask" "F.Paste")
			(net "SMB_VR_3V3STBY_SCL")
		)
		(pad "2" smd circle
			(at 0.40005 0)
			(size 0 0)
			(layers "F.Cu" "F.Mask" "F.Paste")
			(net "SMB_SCM_2_R1_SCL")
		)
	)
	(footprint ""
		(layer "F.Cu")
		(at 105.222548 -386.7912 90)
		(property "Reference" "R746"
			(at 0 0 90)
			(layer "F.SilkS")
			(hide yes)
			(effects
				(font
					(size 1.27 1.27)
				)
			)
		)
		(property "Value" ""
			(at 0 0 90)
			(layer "F.Fab")
			(effects
				(font
					(size 1.27 1.27)
				)
			)
		)
		(duplicate_pad_numbers_are_jumpers no)
		(fp_line
			(start 0.32512 -0.175006)
			(end 0.32512 0.175006)
			(stroke
				(width 0.1)
				(type default)
			)
			(layer "F.Fab")
		)
		(fp_line
			(start -0.32512 -0.175006)
			(end 0.32512 -0.175006)
			(stroke
				(width 0.1)
				(type default)
			)
			(layer "F.Fab")
		)
		(fp_line
			(start 0.32512 0.175006)
			(end -0.32512 0.175006)
			(stroke
				(width 0.1)
				(type default)
			)
			(layer "F.Fab")
		)
		(fp_line
			(start -0.32512 0.175006)
			(end -0.32512 -0.175006)
			(stroke
				(width 0.1)
				(type default)
			)
			(layer "F.Fab")
		)
		(pad "1" smd rect
			(at -0.2667 0 90)
			(size 0.3048 0.381)
			(layers "F.Cu" "F.Mask" "F.Paste")
			(net "RT_CPU1_P1_ADDR2")
		)
		(pad "2" smd rect
			(at 0.2667 0 270)
			(size 0.3048 0.381)
			(layers "F.Cu" "F.Mask" "F.Paste")
			(net "GND")
		)
	)
)
